(kicad_pcb
	(version 20241229)
	(generator "pcbnew")
	(generator_version "9.0")
	(general
		(thickness 1.258)
		(legacy_teardrops no)
	)
	(paper "A4")
	(title_block
		(date "2024-05-27")
		(rev "1.1.2")
		(comment 9 "footprints 61-64 of 64")
	)
	(layers
		(0 "F.Cu" signal)
		(4 "In1.Cu" power)
		(6 "In2.Cu" power)
		(8 "In3.Cu" signal)
		(10 "In4.Cu" signal)
		(2 "B.Cu" signal)
		(9 "F.Adhes" user "F.Adhesive")
		(11 "B.Adhes" user "B.Adhesive")
		(13 "F.Paste" user)
		(15 "B.Paste" user)
		(5 "F.SilkS" user "F.Silkscreen")
		(7 "B.SilkS" user "B.Silkscreen")
		(1 "F.Mask" user)
		(3 "B.Mask" user)
		(17 "Dwgs.User" user "User.Drawings")
		(19 "Cmts.User" user "User.Comments")
		(21 "Eco1.User" user "User.Eco1")
		(23 "Eco2.User" user "User.Eco2")
		(25 "Edge.Cuts" user)
		(27 "Margin" user)
		(31 "F.CrtYd" user "F.Courtyard")
		(29 "B.CrtYd" user "B.Courtyard")
		(35 "F.Fab" user)
		(33 "B.Fab" user)
	)
	(footprint "antmicro-footprints:C_0201"
		(layer "B.Cu")
		(at 152.425 88.85 180)
		(descr "Capacitor SMD 0201")
		(tags "capacitor SMD 0201")
		(property "Reference" "C23"
			(at -1.175 -2.12 0)
			(layer "B.SilkS")
			(effects
				(font
					(size 0.7 0.7)
					(thickness 0.15)
				)
				(justify left bottom mirror)
			)
		)
		(property "Value" "C_100n_0201"
			(at 0 -1.4 0)
			(layer "B.Fab")
			(hide yes)
			(effects
				(font
					(size 0.7 0.7)
					(thickness 0.15)
				)
				(justify left bottom mirror)
			)
		)
		(property "Description" "SMD Multilayer Ceramic Capacitor, 0.1 µF, 6.3 V, 0201 [0603 Metric], ± 10%, X6S, CC Series"
			(at 0 0 180)
			(layer "F.Fab")
			(hide yes)
			(effects
				(font
					(size 1.27 1.27)
					(thickness 0.15)
				)
			)
		)
		(property "Author" "Antmicro"
			(at 304.85 177.7 0)
			(layer "B.Fab")
			(hide yes)
			(effects
				(font
					(size 1 1)
					(thickness 0.15)
				)
				(justify mirror)
			)
		)
		(property "Dielectric" ""
			(at 304.85 177.7 0)
			(layer "B.Fab")
			(hide yes)
			(effects
				(font
					(size 1 1)
					(thickness 0.15)
				)
				(justify mirror)
			)
		)
		(property "License" "Apache-2.0"
			(at 304.85 177.7 0)
			(layer "B.Fab")
			(hide yes)
			(effects
				(font
					(size 1 1)
					(thickness 0.15)
				)
				(justify mirror)
			)
		)
		(property "MPN" "CC0201KRX6S5BB104"
			(at 304.85 177.7 0)
			(layer "B.Fab")
			(hide yes)
			(effects
				(font
					(size 1 1)
					(thickness 0.15)
				)
				(justify mirror)
			)
		)
		(property "Manufacturer" "YAGEO"
			(at 304.85 177.7 0)
			(layer "B.Fab")
			(hide yes)
			(effects
				(font
					(size 1 1)
					(thickness 0.15)
				)
				(justify mirror)
			)
		)
		(property "Public" "False"
			(at 304.85 177.7 0)
			(layer "B.Fab")
			(hide yes)
			(effects
				(font
					(size 1 1)
					(thickness 0.15)
				)
				(justify mirror)
			)
		)
		(property "Val" "100n"
			(at 304.85 177.7 0)
			(layer "B.Fab")
			(hide yes)
			(effects
				(font
					(size 1 1)
					(thickness 0.15)
				)
				(justify mirror)
			)
		)
		(property "Voltage" ""
			(at 304.85 177.7 0)
			(layer "B.Fab")
			(hide yes)
			(effects
				(font
					(size 1 1)
					(thickness 0.15)
				)
				(justify mirror)
			)
		)
		(sheetname "DDR5")
		(sheetfile "ddr5.kicad_sch")
		(attr smd)
		(fp_rect
			(start -0.7 0.35)
			(end 0.7 -0.35)
			(stroke
				(width 0.05)
				(type default)
			)
			(fill no)
			(layer "B.CrtYd")
		)
		(fp_rect
			(start 0.3 -0.15)
			(end -0.301 0.149)
			(stroke
				(width 0.15)
				(type solid)
			)
			(fill no)
			(layer "B.Fab")
		)
		(pad "" smd roundrect
			(at -0.349 0.002 180)
			(size 0.318 0.36)
			(layers "B.Paste")
			(roundrect_rratio 0.25)
		)
		(pad "" smd roundrect
			(at 0.341 0.002 180)
			(size 0.318 0.36)
			(layers "B.Paste")
			(roundrect_rratio 0.25)
		)
		(pad "1" smd roundrect
			(at -0.321 0.002 180)
			(size 0.46 0.4)
			(layers "B.Cu" "B.Mask")
			(roundrect_rratio 0.25)
			(net 18 "VDD")
			(pintype "passive")
		)
		(pad "2" smd roundrect
			(at 0.32 0.002 180)
			(size 0.46 0.4)
			(layers "B.Cu" "B.Mask")
			(roundrect_rratio 0.25)
			(net 1 "GND")
			(pintype "passive")
		)
	)
	(footprint "antmicro-footprints:R_0402_1005Metric"
		(layer "B.Cu")
		(at 156.9 85.6)
		(descr "Resistor SMD 0402")
		(tags "resistor SMD 0402")
		(property "Reference" "R2"
			(at 2.4 0.33 180)
			(layer "B.SilkS")
			(effects
				(font
					(size 0.7 0.7)
					(thickness 0.15)
				)
				(justify left bottom mirror)
			)
		)
		(property "Value" "R_0R_0402"
			(at 0 -1.4 180)
			(layer "B.Fab")
			(hide yes)
			(effects
				(font
					(size 0.7 0.7)
					(thickness 0.15)
				)
				(justify left bottom mirror)
			)
		)
		(property "Description" "0R resistor in 0402 package with unspecified tolerance"
			(at 0 0 0)
			(layer "F.Fab")
			(hide yes)
			(effects
				(font
					(size 1.27 1.27)
					(thickness 0.15)
				)
			)
		)
		(property "Author" "Antmicro"
			(at 0 0 0)
			(layer "B.Fab")
			(hide yes)
			(effects
				(font
					(size 1 1)
					(thickness 0.15)
				)
				(justify mirror)
			)
		)
		(property "Current" "1A"
			(at 0 0 0)
			(layer "B.Fab")
			(hide yes)
			(effects
				(font
					(size 1 1)
					(thickness 0.15)
				)
				(justify mirror)
			)
		)
		(property "License" "Apache-2.0"
			(at 0 0 0)
			(layer "B.Fab")
			(hide yes)
			(effects
				(font
					(size 1 1)
					(thickness 0.15)
				)
				(justify mirror)
			)
		)
		(property "MPN" "ERJ2GE0R00X"
			(at 0 0 0)
			(layer "B.Fab")
			(hide yes)
			(effects
				(font
					(size 1 1)
					(thickness 0.15)
				)
				(justify mirror)
			)
		)
		(property "Manufacturer" "Panasonic"
			(at 0 0 0)
			(layer "B.Fab")
			(hide yes)
			(effects
				(font
					(size 1 1)
					(thickness 0.15)
				)
				(justify mirror)
			)
		)
		(property "Tolerance" ""
			(at 0 0 0)
			(layer "B.Fab")
			(hide yes)
			(effects
				(font
					(size 1 1)
					(thickness 0.15)
				)
				(justify mirror)
			)
		)
		(property "Val" "0R"
			(at 0 0 0)
			(layer "B.Fab")
			(hide yes)
			(effects
				(font
					(size 1 1)
					(thickness 0.15)
				)
				(justify mirror)
			)
		)
		(sheetname "DDR5")
		(sheetfile "ddr5.kicad_sch")
		(attr smd)
		(fp_rect
			(start -0.925 0.47)
			(end 0.925 -0.47)
			(stroke
				(width 0.05)
				(type default)
			)
			(fill no)
			(layer "B.CrtYd")
		)
		(fp_rect
			(start -0.5 0.25)
			(end 0.5 -0.25)
			(stroke
				(width 0.15)
				(type solid)
			)
			(fill no)
			(layer "B.Fab")
		)
		(pad "1" smd roundrect
			(at -0.48 0)
			(size 0.59 0.64)
			(layers "B.Cu" "B.Mask" "B.Paste")
			(roundrect_rratio 0.25)
			(net 58 "/DDR5/R_ODT_CA_A")
			(pintype "passive")
		)
		(pad "2" smd roundrect
			(at 0.48 0)
			(size 0.59 0.64)
			(layers "B.Cu" "B.Mask" "B.Paste")
			(roundrect_rratio 0.25)
			(net 55 "OTD_CA_A")
			(pintype "passive")
		)
	)
	(footprint "antmicro-footprints:C_0201"
		(layer "B.Cu")
		(at 154.75 82.45 180)
		(descr "Capacitor SMD 0201")
		(tags "capacitor SMD 0201")
		(property "Reference" "C5"
			(at -0.83 0.39 0)
			(layer "B.SilkS")
			(effects
				(font
					(size 0.7 0.7)
					(thickness 0.15)
				)
				(justify left bottom mirror)
			)
		)
		(property "Value" "C_100n_0201"
			(at 0 -1.4 0)
			(layer "B.Fab")
			(hide yes)
			(effects
				(font
					(size 0.7 0.7)
					(thickness 0.15)
				)
				(justify left bottom mirror)
			)
		)
		(property "Description" "SMD Multilayer Ceramic Capacitor, 0.1 µF, 6.3 V, 0201 [0603 Metric], ± 10%, X6S, CC Series"
			(at 0 0 180)
			(layer "F.Fab")
			(hide yes)
			(effects
				(font
					(size 1.27 1.27)
					(thickness 0.15)
				)
			)
		)
		(property "Author" "Antmicro"
			(at 309.5 164.9 0)
			(layer "B.Fab")
			(hide yes)
			(effects
				(font
					(size 1 1)
					(thickness 0.15)
				)
				(justify mirror)
			)
		)
		(property "Dielectric" ""
			(at 309.5 164.9 0)
			(layer "B.Fab")
			(hide yes)
			(effects
				(font
					(size 1 1)
					(thickness 0.15)
				)
				(justify mirror)
			)
		)
		(property "License" "Apache-2.0"
			(at 309.5 164.9 0)
			(layer "B.Fab")
			(hide yes)
			(effects
				(font
					(size 1 1)
					(thickness 0.15)
				)
				(justify mirror)
			)
		)
		(property "MPN" "CC0201KRX6S5BB104"
			(at 309.5 164.9 0)
			(layer "B.Fab")
			(hide yes)
			(effects
				(font
					(size 1 1)
					(thickness 0.15)
				)
				(justify mirror)
			)
		)
		(property "Manufacturer" "YAGEO"
			(at 309.5 164.9 0)
			(layer "B.Fab")
			(hide yes)
			(effects
				(font
					(size 1 1)
					(thickness 0.15)
				)
				(justify mirror)
			)
		)
		(property "Public" "False"
			(at 309.5 164.9 0)
			(layer "B.Fab")
			(hide yes)
			(effects
				(font
					(size 1 1)
					(thickness 0.15)
				)
				(justify mirror)
			)
		)
		(property "Val" "100n"
			(at 309.5 164.9 0)
			(layer "B.Fab")
			(hide yes)
			(effects
				(font
					(size 1 1)
					(thickness 0.15)
				)
				(justify mirror)
			)
		)
		(property "Voltage" ""
			(at 309.5 164.9 0)
			(layer "B.Fab")
			(hide yes)
			(effects
				(font
					(size 1 1)
					(thickness 0.15)
				)
				(justify mirror)
			)
		)
		(sheetname "DDR5")
		(sheetfile "ddr5.kicad_sch")
		(attr smd)
		(fp_rect
			(start -0.7 0.35)
			(end 0.7 -0.35)
			(stroke
				(width 0.05)
				(type default)
			)
			(fill no)
			(layer "B.CrtYd")
		)
		(fp_rect
			(start 0.3 -0.15)
			(end -0.301 0.149)
			(stroke
				(width 0.15)
				(type solid)
			)
			(fill no)
			(layer "B.Fab")
		)
		(pad "" smd roundrect
			(at -0.349 0.002 180)
			(size 0.318 0.36)
			(layers "B.Paste")
			(roundrect_rratio 0.25)
		)
		(pad "" smd roundrect
			(at 0.341 0.002 180)
			(size 0.318 0.36)
			(layers "B.Paste")
			(roundrect_rratio 0.25)
		)
		(pad "1" smd roundrect
			(at -0.321 0.002 180)
			(size 0.46 0.4)
			(layers "B.Cu" "B.Mask")
			(roundrect_rratio 0.25)
			(net 2 "VDDQ")
			(pintype "passive")
		)
		(pad "2" smd roundrect
			(at 0.32 0.002 180)
			(size 0.46 0.4)
			(layers "B.Cu" "B.Mask")
			(roundrect_rratio 0.25)
			(net 1 "GND")
			(pintype "passive")
		)
	)
	(footprint "antmicro-footprints:C_0201"
		(layer "B.Cu")
		(at 150.825 87.625 180)
		(descr "Capacitor SMD 0201")
		(tags "capacitor SMD 0201")
		(property "Reference" "C2"
			(at -0.675 -2.205 0)
			(layer "B.SilkS")
			(effects
				(font
					(size 0.7 0.7)
					(thickness 0.15)
				)
				(justify left bottom mirror)
			)
		)
		(property "Value" "C_100n_0201"
			(at 0 -1.4 0)
			(layer "B.Fab")
			(hide yes)
			(effects
				(font
					(size 0.7 0.7)
					(thickness 0.15)
				)
				(justify left bottom mirror)
			)
		)
		(property "Description" "SMD Multilayer Ceramic Capacitor, 0.1 µF, 6.3 V, 0201 [0603 Metric], ± 10%, X6S, CC Series"
			(at 0 0 180)
			(layer "F.Fab")
			(hide yes)
			(effects
				(font
					(size 1.27 1.27)
					(thickness 0.15)
				)
			)
		)
		(property "Author" "Antmicro"
			(at 301.65 175.25 0)
			(layer "B.Fab")
			(hide yes)
			(effects
				(font
					(size 1 1)
					(thickness 0.15)
				)
				(justify mirror)
			)
		)
		(property "Dielectric" ""
			(at 301.65 175.25 0)
			(layer "B.Fab")
			(hide yes)
			(effects
				(font
					(size 1 1)
					(thickness 0.15)
				)
				(justify mirror)
			)
		)
		(property "License" "Apache-2.0"
			(at 301.65 175.25 0)
			(layer "B.Fab")
			(hide yes)
			(effects
				(font
					(size 1 1)
					(thickness 0.15)
				)
				(justify mirror)
			)
		)
		(property "MPN" "CC0201KRX6S5BB104"
			(at 301.65 175.25 0)
			(layer "B.Fab")
			(hide yes)
			(effects
				(font
					(size 1 1)
					(thickness 0.15)
				)
				(justify mirror)
			)
		)
		(property "Manufacturer" "YAGEO"
			(at 301.65 175.25 0)
			(layer "B.Fab")
			(hide yes)
			(effects
				(font
					(size 1 1)
					(thickness 0.15)
				)
				(justify mirror)
			)
		)
		(property "Public" "False"
			(at 301.65 175.25 0)
			(layer "B.Fab")
			(hide yes)
			(effects
				(font
					(size 1 1)
					(thickness 0.15)
				)
				(justify mirror)
			)
		)
		(property "Val" "100n"
			(at 301.65 175.25 0)
			(layer "B.Fab")
			(hide yes)
			(effects
				(font
					(size 1 1)
					(thickness 0.15)
				)
				(justify mirror)
			)
		)
		(property "Voltage" ""
			(at 301.65 175.25 0)
			(layer "B.Fab")
			(hide yes)
			(effects
				(font
					(size 1 1)
					(thickness 0.15)
				)
				(justify mirror)
			)
		)
		(sheetname "DDR5")
		(sheetfile "ddr5.kicad_sch")
		(attr smd)
		(fp_rect
			(start -0.7 0.35)
			(end 0.7 -0.35)
			(stroke
				(width 0.05)
				(type default)
			)
			(fill no)
			(layer "B.CrtYd")
		)
		(fp_rect
			(start 0.3 -0.15)
			(end -0.301 0.149)
			(stroke
				(width 0.15)
				(type solid)
			)
			(fill no)
			(layer "B.Fab")
		)
		(pad "" smd roundrect
			(at -0.349 0.002 180)
			(size 0.318 0.36)
			(layers "B.Paste")
			(roundrect_rratio 0.25)
		)
		(pad "" smd roundrect
			(at 0.341 0.002 180)
			(size 0.318 0.36)
			(layers "B.Paste")
			(roundrect_rratio 0.25)
		)
		(pad "1" smd roundrect
			(at -0.321 0.002 180)
			(size 0.46 0.4)
			(layers "B.Cu" "B.Mask")
			(roundrect_rratio 0.25)
			(net 2 "VDDQ")
			(pintype "passive")
		)
		(pad "2" smd roundrect
			(at 0.32 0.002 180)
			(size 0.46 0.4)
			(layers "B.Cu" "B.Mask")
			(roundrect_rratio 0.25)
			(net 1 "GND")
			(pintype "passive")
		)
	)
)
